#ISCELL
  pure_quanta quanta_title_block_c *
  *
#ISCELL
  standard offpage *
  page125_i1
#ISCELL
  standard offpage *
  page125_i10
#ISCELL
  standard offpage *
  page125_i11
#CELL
  pure_quanta q_res *
  page125_i13
#CELL
  pure_quanta q_res *
  page125_i15
#CELL
  pure_quanta q_res *
  page125_i17
#ISCELL
  standard offpage *
  page125_i2
#CELL
  pure_quanta q_res *
  page125_i24
#CELL
  pure_quanta q_res *
  page125_i26
#ISCELL
  logical_power universal_power *
  page125_i27
#ISCELL
  standard offpage *
  page125_i28
#ISCELL
  logical_power universal_power *
  page125_i29
#CELL
  pure_quanta q_res *
  page125_i3
#ISCELL
  standard offpage *
  page125_i30
#CELL
  pure_quanta q_res *
  page125_i5
#CELL
  pure_quanta q_res *
  page125_i56
#ISCELL
  logical_power universal_power *
  page125_i57
#CELL
  pure_quanta q_res *
  page125_i58
#ISCELL
  logical_power universal_power *
  page125_i59
#CELL
  pure_quanta q_res *
  page125_i60
#ISCELL
  logical_power universal_power *
  page125_i61
#CELL
  pure_quanta q_res *
  page125_i62
#ISCELL
  logical_power universal_power *
  page125_i63
#CELL
  pure_quanta q_res *
  page125_i64
#CELL
  pure_quanta q_res *
  page125_i65
#CELL
  pure_quanta q_res *
  page125_i66
#ISCELL
  standard offpage *
  page125_i67
#CELL
  pure_quanta q_res *
  page125_i68
#ISCELL
  standard offpage *
  page125_i69
#CELL
  pure_quanta q_res *
  page125_i7
#CELL
  pure_quanta q_res *
  page125_i70
#ISCELL
  standard offpage *
  page125_i71
#CELL
  pure_quanta q_res *
  page125_i72
#ISCELL
  standard offpage *
  page125_i73
#ISCELL
  standard offpage *
  page125_i8
#ISCELL
  standard offpage *
  page125_i9
